(kicad_pcb
	(version 20260206)
	(generator "pcbnew")
	(generator_version "10.0")
	(general
		(thickness 1.6)
		(legacy_teardrops no)
	)
	(paper "A4")
	(title_block
		(title "04192023_DAF0TMB3IC0_F0TG_MB_C_brd_V02_OCP.brd")
		(comment 1 "Grand Teton / footprints 2030-2034 of 8354")
	)
	(layers
		(0 "F.Cu" signal "TOP")
		(4 "In1.Cu" signal "GND")
		(6 "In2.Cu" signal "IN1")
		(8 "In3.Cu" signal "GND1")
		(10 "In4.Cu" signal "IN2")
		(12 "In5.Cu" signal "GND2")
		(14 "In6.Cu" signal "IN3")
		(16 "In7.Cu" signal "GND3")
		(18 "In8.Cu" signal "VCC")
		(20 "In9.Cu" signal "VCC1")
		(22 "In10.Cu" signal "GND4")
		(24 "In11.Cu" signal "IN4")
		(26 "In12.Cu" signal "GND5")
		(28 "In13.Cu" signal "IN5")
		(30 "In14.Cu" signal "GND6")
		(32 "In15.Cu" signal "IN6")
		(34 "In16.Cu" signal "GND7")
		(2 "B.Cu" signal "BOTTOM")
		(9 "F.Adhes" user "F.Adhesive")
		(11 "B.Adhes" user "B.Adhesive")
		(13 "F.Paste" user "Package Geometry/Pastemask Top")
		(15 "B.Paste" user "Package Geometry/Pastemask Bottom")
		(5 "F.SilkS" user "Ref Des/Silkscreen Top")
		(7 "B.SilkS" user "Ref Des/Silkscreen Bottom")
		(1 "F.Mask" user "Board Geometry/Soldermask Top")
		(3 "B.Mask" user "Board Geometry/Soldermask Bottom")
		(17 "Dwgs.User" user "User.Drawings")
		(19 "Cmts.User" user "User.Comments")
		(21 "Eco1.User" user "User.Eco1")
		(23 "Eco2.User" user "User.Eco2")
		(25 "Edge.Cuts" user "Board Geometry/Outline")
		(27 "Margin" user)
		(31 "F.CrtYd" user "Package Geometry/Place Bound Top")
		(29 "B.CrtYd" user "Package Geometry/Place Bound Bottom")
		(35 "F.Fab" user "Ref Des/Assembly Top")
		(33 "B.Fab" user "Ref Des/Assembly Bottom")
	)
	(footprint ""
		(layer "F.Cu")
		(at 163.178744 -344.153998 -90)
		(property "Reference" "PR407"
			(at 0 0 270)
			(layer "F.SilkS")
			(hide yes)
			(effects
				(font
					(size 1.27 1.27)
				)
			)
		)
		(property "Value" ""
			(at 0 0 270)
			(layer "F.Fab")
			(effects
				(font
					(size 1.27 1.27)
				)
			)
		)
		(duplicate_pad_numbers_are_jumpers no)
		(fp_line
			(start -0.7874 0.4064)
			(end -0.7874 -0.4064)
			(stroke
				(width 0.1524)
				(type default)
			)
			(layer "F.SilkS")
		)
		(fp_line
			(start 0.7874 0.4064)
			(end -0.7874 0.4064)
			(stroke
				(width 0.1524)
				(type default)
			)
			(layer "F.SilkS")
		)
		(fp_line
			(start -0.7874 -0.4064)
			(end 0.7874 -0.4064)
			(stroke
				(width 0.1524)
				(type default)
			)
			(layer "F.SilkS")
		)
		(fp_line
			(start 0.7874 -0.4064)
			(end 0.7874 0.4064)
			(stroke
				(width 0.1524)
				(type default)
			)
			(layer "F.SilkS")
		)
		(fp_line
			(start -0.67945 0.3048)
			(end -0.67945 -0.305054)
			(stroke
				(width 0.1)
				(type default)
			)
			(layer "F.Fab")
		)
		(fp_line
			(start -0.12065 0.3048)
			(end -0.67945 0.3048)
			(stroke
				(width 0.1)
				(type default)
			)
			(layer "F.Fab")
		)
		(fp_line
			(start 0.120396 0.3048)
			(end 0.120396 0.2794)
			(stroke
				(width 0.1)
				(type default)
			)
			(layer "F.Fab")
		)
		(fp_line
			(start 0.67945 0.3048)
			(end 0.120396 0.3048)
			(stroke
				(width 0.1)
				(type default)
			)
			(layer "F.Fab")
		)
		(fp_line
			(start -0.12065 0.2794)
			(end -0.12065 0.3048)
			(stroke
				(width 0.1)
				(type default)
			)
			(layer "F.Fab")
		)
		(fp_line
			(start 0.120396 0.2794)
			(end -0.12065 0.2794)
			(stroke
				(width 0.1)
				(type default)
			)
			(layer "F.Fab")
		)
		(fp_line
			(start -0.12065 -0.2794)
			(end 0.12065 -0.2794)
			(stroke
				(width 0.1)
				(type default)
			)
			(layer "F.Fab")
		)
		(fp_line
			(start 0.12065 -0.2794)
			(end 0.12065 -0.3048)
			(stroke
				(width 0.1)
				(type default)
			)
			(layer "F.Fab")
		)
		(fp_line
			(start 0.12065 -0.3048)
			(end 0.67945 -0.3048)
			(stroke
				(width 0.1)
				(type default)
			)
			(layer "F.Fab")
		)
		(fp_line
			(start 0.67945 -0.3048)
			(end 0.67945 0.3048)
			(stroke
				(width 0.1)
				(type default)
			)
			(layer "F.Fab")
		)
		(fp_line
			(start -0.67945 -0.305054)
			(end -0.12065 -0.305054)
			(stroke
				(width 0.1)
				(type default)
			)
			(layer "F.Fab")
		)
		(fp_line
			(start -0.12065 -0.305054)
			(end -0.12065 -0.2794)
			(stroke
				(width 0.1)
				(type default)
			)
			(layer "F.Fab")
		)
		(pad "1" smd circle
			(at -0.40005 0 270)
			(size 0 0)
			(layers "F.Cu" "F.Mask" "F.Paste")
			(net "NC_PVDD11_S3_P1_IMON4")
		)
		(pad "2" smd circle
			(at 0.40005 0 270)
			(size 0 0)
			(layers "F.Cu" "F.Mask" "F.Paste")
			(net "GND")
		)
	)
	(footprint ""
		(layer "F.Cu")
		(at 423.779696 -357.688134 -90)
		(property "Reference" "PR36"
			(at 0 0 270)
			(layer "F.SilkS")
			(hide yes)
			(effects
				(font
					(size 1.27 1.27)
				)
			)
		)
		(property "Value" ""
			(at 0 0 270)
			(layer "F.Fab")
			(effects
				(font
					(size 1.27 1.27)
				)
			)
		)
		(duplicate_pad_numbers_are_jumpers no)
		(fp_line
			(start -0.7874 0.4064)
			(end -0.7874 -0.4064)
			(stroke
				(width 0.1524)
				(type default)
			)
			(layer "F.SilkS")
		)
		(fp_line
			(start 0.7874 0.4064)
			(end -0.7874 0.4064)
			(stroke
				(width 0.1524)
				(type default)
			)
			(layer "F.SilkS")
		)
		(fp_line
			(start -0.7874 -0.4064)
			(end 0.7874 -0.4064)
			(stroke
				(width 0.1524)
				(type default)
			)
			(layer "F.SilkS")
		)
		(fp_line
			(start 0.7874 -0.4064)
			(end 0.7874 0.4064)
			(stroke
				(width 0.1524)
				(type default)
			)
			(layer "F.SilkS")
		)
		(fp_line
			(start -0.67945 0.3048)
			(end -0.67945 -0.305054)
			(stroke
				(width 0.1)
				(type default)
			)
			(layer "F.Fab")
		)
		(fp_line
			(start -0.12065 0.3048)
			(end -0.67945 0.3048)
			(stroke
				(width 0.1)
				(type default)
			)
			(layer "F.Fab")
		)
		(fp_line
			(start 0.120396 0.3048)
			(end 0.120396 0.2794)
			(stroke
				(width 0.1)
				(type default)
			)
			(layer "F.Fab")
		)
		(fp_line
			(start 0.67945 0.3048)
			(end 0.120396 0.3048)
			(stroke
				(width 0.1)
				(type default)
			)
			(layer "F.Fab")
		)
		(fp_line
			(start -0.12065 0.2794)
			(end -0.12065 0.3048)
			(stroke
				(width 0.1)
				(type default)
			)
			(layer "F.Fab")
		)
		(fp_line
			(start 0.120396 0.2794)
			(end -0.12065 0.2794)
			(stroke
				(width 0.1)
				(type default)
			)
			(layer "F.Fab")
		)
		(fp_line
			(start -0.12065 -0.2794)
			(end 0.12065 -0.2794)
			(stroke
				(width 0.1)
				(type default)
			)
			(layer "F.Fab")
		)
		(fp_line
			(start 0.12065 -0.2794)
			(end 0.12065 -0.3048)
			(stroke
				(width 0.1)
				(type default)
			)
			(layer "F.Fab")
		)
		(fp_line
			(start 0.12065 -0.3048)
			(end 0.67945 -0.3048)
			(stroke
				(width 0.1)
				(type default)
			)
			(layer "F.Fab")
		)
		(fp_line
			(start 0.67945 -0.3048)
			(end 0.67945 0.3048)
			(stroke
				(width 0.1)
				(type default)
			)
			(layer "F.Fab")
		)
		(fp_line
			(start -0.67945 -0.305054)
			(end -0.12065 -0.305054)
			(stroke
				(width 0.1)
				(type default)
			)
			(layer "F.Fab")
		)
		(fp_line
			(start -0.12065 -0.305054)
			(end -0.12065 -0.2794)
			(stroke
				(width 0.1)
				(type default)
			)
			(layer "F.Fab")
		)
		(pad "1" smd circle
			(at -0.40005 0 270)
			(size 0 0)
			(layers "F.Cu" "F.Mask" "F.Paste")
			(net "NC_PVDD11_S3_P0_IMON8")
		)
		(pad "2" smd circle
			(at 0.40005 0 270)
			(size 0 0)
			(layers "F.Cu" "F.Mask" "F.Paste")
			(net "GND")
		)
	)
	(footprint ""
		(layer "F.Cu")
		(at 281.827732 -392.705844 90)
		(property "Reference" "R355"
			(at 0 0 90)
			(layer "F.SilkS")
			(hide yes)
			(effects
				(font
					(size 1.27 1.27)
				)
			)
		)
		(property "Value" ""
			(at 0 0 90)
			(layer "F.Fab")
			(effects
				(font
					(size 1.27 1.27)
				)
			)
		)
		(duplicate_pad_numbers_are_jumpers no)
		(fp_line
			(start 0.7874 -0.4064)
			(end 0.7874 0.4064)
			(stroke
				(width 0.1524)
				(type default)
			)
			(layer "F.SilkS")
		)
		(fp_line
			(start -0.7874 -0.4064)
			(end 0.7874 -0.4064)
			(stroke
				(width 0.1524)
				(type default)
			)
			(layer "F.SilkS")
		)
		(fp_line
			(start 0.7874 0.4064)
			(end -0.7874 0.4064)
			(stroke
				(width 0.1524)
				(type default)
			)
			(layer "F.SilkS")
		)
		(fp_line
			(start -0.7874 0.4064)
			(end -0.7874 -0.4064)
			(stroke
				(width 0.1524)
				(type default)
			)
			(layer "F.SilkS")
		)
		(fp_line
			(start -0.12065 -0.305054)
			(end -0.12065 -0.2794)
			(stroke
				(width 0.1)
				(type default)
			)
			(layer "F.Fab")
		)
		(fp_line
			(start -0.67945 -0.305054)
			(end -0.12065 -0.305054)
			(stroke
				(width 0.1)
				(type default)
			)
			(layer "F.Fab")
		)
		(fp_line
			(start 0.67945 -0.3048)
			(end 0.67945 0.3048)
			(stroke
				(width 0.1)
				(type default)
			)
			(layer "F.Fab")
		)
		(fp_line
			(start 0.12065 -0.3048)
			(end 0.67945 -0.3048)
			(stroke
				(width 0.1)
				(type default)
			)
			(layer "F.Fab")
		)
		(fp_line
			(start 0.12065 -0.2794)
			(end 0.12065 -0.3048)
			(stroke
				(width 0.1)
				(type default)
			)
			(layer "F.Fab")
		)
		(fp_line
			(start -0.12065 -0.2794)
			(end 0.12065 -0.2794)
			(stroke
				(width 0.1)
				(type default)
			)
			(layer "F.Fab")
		)
		(fp_line
			(start 0.120396 0.2794)
			(end -0.12065 0.2794)
			(stroke
				(width 0.1)
				(type default)
			)
			(layer "F.Fab")
		)
		(fp_line
			(start -0.12065 0.2794)
			(end -0.12065 0.3048)
			(stroke
				(width 0.1)
				(type default)
			)
			(layer "F.Fab")
		)
		(fp_line
			(start 0.67945 0.3048)
			(end 0.120396 0.3048)
			(stroke
				(width 0.1)
				(type default)
			)
			(layer "F.Fab")
		)
		(fp_line
			(start 0.120396 0.3048)
			(end 0.120396 0.2794)
			(stroke
				(width 0.1)
				(type default)
			)
			(layer "F.Fab")
		)
		(fp_line
			(start -0.12065 0.3048)
			(end -0.67945 0.3048)
			(stroke
				(width 0.1)
				(type default)
			)
			(layer "F.Fab")
		)
		(fp_line
			(start -0.67945 0.3048)
			(end -0.67945 -0.305054)
			(stroke
				(width 0.1)
				(type default)
			)
			(layer "F.Fab")
		)
		(pad "1" smd circle
			(at -0.40005 0 90)
			(size 0 0)
			(layers "F.Cu" "F.Mask" "F.Paste")
			(net "P3V3_AUX")
		)
		(pad "2" smd circle
			(at 0.40005 0 90)
			(size 0 0)
			(layers "F.Cu" "F.Mask" "F.Paste")
			(net "P12V_HSC_TEMP_ALERT_R_N")
		)
	)
	(footprint ""
		(layer "F.Cu")
		(at 69.431154 -370.57203 -90)
		(property "Reference" "C811"
			(at 0 0 270)
			(layer "F.SilkS")
			(hide yes)
			(effects
				(font
					(size 1.27 1.27)
				)
			)
		)
		(property "Value" ""
			(at 0 0 270)
			(layer "F.Fab")
			(effects
				(font
					(size 1.27 1.27)
				)
			)
		)
		(duplicate_pad_numbers_are_jumpers no)
		(fp_line
			(start -0.299974 0.150114)
			(end -0.299974 -0.150114)
			(stroke
				(width 0.1)
				(type default)
			)
			(layer "F.Fab")
		)
		(fp_line
			(start 0.299974 0.150114)
			(end -0.299974 0.150114)
			(stroke
				(width 0.1)
				(type default)
			)
			(layer "F.Fab")
		)
		(fp_line
			(start -0.299974 -0.150114)
			(end 0.299974 -0.150114)
			(stroke
				(width 0.1)
				(type default)
			)
			(layer "F.Fab")
		)
		(fp_line
			(start 0.299974 -0.150114)
			(end 0.299974 0.150114)
			(stroke
				(width 0.1)
				(type default)
			)
			(layer "F.Fab")
		)
		(pad "1" smd rect
			(at -0.2667 0 270)
			(size 0.3048 0.381)
			(layers "F.Cu" "F.Mask" "F.Paste")
			(net "P5E_CPU1_P0_TX_C_DP<13>")
		)
		(pad "2" smd rect
			(at 0.2667 0 270)
			(size 0.3048 0.381)
			(layers "F.Cu" "F.Mask" "F.Paste")
			(net "P5E_CPU1_P0_TX_DP<13>")
		)
	)
	(footprint ""
		(layer "F.Cu")
		(at 16.56207 -388.854188)
		(property "Reference" "PU6511"
			(at -5.86232 -8.184642 0)
			(unlocked yes)
			(layer "F.SilkS")
			(effects
				(font
					(size 0.7874 0.5842)
					(thickness 0.1524)
				)
				(justify left)
			)
		)
		(property "Value" ""
			(at 0 0 0)
			(layer "F.Fab")
			(effects
				(font
					(size 1.27 1.27)
				)
			)
		)
		(duplicate_pad_numbers_are_jumpers no)
		(fp_line
			(start -2.500122 -2.999994)
			(end -2.24409 -2.999994)
			(stroke
				(width 0.1524)
				(type default)
			)
			(layer "F.SilkS")
		)
		(fp_line
			(start -2.500122 -2.529078)
			(end -2.500122 -2.999994)
			(stroke
				(width 0.1524)
				(type default)
			)
			(layer "F.SilkS")
		)
		(fp_line
			(start -2.500122 0.6604)
			(end -2.500122 0.229108)
			(stroke
				(width 0.1524)
				(type default)
			)
			(layer "F.SilkS")
		)
		(fp_line
			(start -2.500122 2.999994)
			(end -2.500122 2.339594)
			(stroke
				(width 0.1524)
				(type default)
			)
			(layer "F.SilkS")
		)
		(fp_line
			(start -2.2987 2.999994)
			(end -2.500122 2.999994)
			(stroke
				(width 0.1524)
				(type default)
			)
			(layer "F.SilkS")
		)
		(fp_line
			(start 2.31394 -2.999994)
			(end 2.500122 -2.999994)
			(stroke
				(width 0.1524)
				(type default)
			)
			(layer "F.SilkS")
		)
		(fp_line
			(start 2.500122 -2.999994)
			(end 2.500122 -2.44348)
			(stroke
				(width 0.1524)
				(type default)
			)
			(layer "F.SilkS")
		)
		(fp_line
			(start 2.500122 2.339594)
			(end 2.500122 2.999994)
			(stroke
				(width 0.1524)
				(type default)
			)
			(layer "F.SilkS")
		)
		(fp_line
			(start 2.500122 2.999994)
			(end 2.2987 2.999994)
			(stroke
				(width 0.1524)
				(type default)
			)
			(layer "F.SilkS")
		)
		(fp_poly
			(pts
				(xy -3.721862 -2.76352) (xy -2.77876 -2.450338) (xy -3.09372 -3.391662)
			)
			(stroke
				(width 0)
				(type default)
			)
			(fill yes)
			(layer "F.SilkS")
		)
		(fp_line
			(start -2.500122 -2.999994)
			(end 2.500122 -2.999994)
			(stroke
				(width 0.1)
				(type default)
			)
			(layer "F.Fab")
		)
		(fp_line
			(start -2.500122 2.999994)
			(end -2.500122 -2.999994)
			(stroke
				(width 0.1)
				(type default)
			)
			(layer "F.Fab")
		)
		(fp_line
			(start 2.500122 -2.999994)
			(end 2.500122 2.999994)
			(stroke
				(width 0.1)
				(type default)
			)
			(layer "F.Fab")
		)
		(fp_line
			(start 2.500122 2.999994)
			(end -2.500122 2.999994)
			(stroke
				(width 0.1)
				(type default)
			)
			(layer "F.Fab")
		)
		(fp_poly
			(pts
				(xy -4.218432 -2.783078) (xy -4.218432 -1.767078) (xy -3.202432 -2.275078)
			)
			(stroke
				(width 0)
				(type default)
			)
			(fill yes)
			(layer "F.Fab")
		)
		(pad "1" smd rect
			(at -2.400046 -2.275078 90)
			(size 0.2286 0.6096)
			(layers "F.Cu" "F.Mask" "F.Paste")
			(net "P0V9_RETIMER_CPU1_VOS1")
		)
		(pad "2" smd rect
			(at -2.400046 -1.82499 90)
			(size 0.2286 0.6096)
			(layers "F.Cu" "F.Mask" "F.Paste")
			(net "GND")
		)
		(pad "3" smd rect
			(at -2.400046 -1.374902 90)
			(size 0.2286 0.6096)
			(layers "F.Cu" "F.Mask" "F.Paste")
			(net "P0V9_RETIMER_CPU1_VCC1")
		)
		(pad "4" smd rect
			(at -2.400046 -0.925068 90)
			(size 0.2286 0.6096)
			(layers "F.Cu" "F.Mask" "F.Paste")
			(net "P0V9_RETIMER_CPU1_PVCC")
		)
		(pad "5" smd rect
			(at -2.400046 -0.47498 90)
			(size 0.2286 0.6096)
			(layers "F.Cu" "F.Mask" "F.Paste")
			(net "GND")
		)
		(pad "6" smd rect
			(at -2.400046 -0.024892 90)
			(size 0.2286 0.6096)
			(layers "F.Cu" "F.Mask" "F.Paste")
			(net "NC_PV09_RETIMER_CPU1_GL1_1")
		)
		(pad "7_9-20_24" smd circle
			(at 0 1.150112 90)
			(size 0 0)
			(layers "F.Cu" "F.Mask" "F.Paste")
			(net "GND")
		)
		(pad "10_19" smd rect
			(at 0 2.899918 90)
			(size 0.6096 4.318)
			(layers "F.Cu" "F.Mask" "F.Paste")
			(net "SW_P0V9_RETIMER_CPU1_SW1")
		)
		(pad "25_29" smd rect
			(at 1.549908 -1.279906 270)
			(size 2.0574 2.3114)
			(layers "F.Cu" "F.Mask" "F.Paste")
			(net "SW_P12V_AUX_P0V9_RETIMER_CPU1_FLT")
		)
		(pad "30" smd rect
			(at 2.05994 -2.899918)
			(size 0.2286 0.6096)
			(layers "F.Cu" "F.Mask" "F.Paste")
			(net "SW_P12V_AUX_P0V9_RETIMER_CPU1_FLT")
		)
		(pad "31" smd rect
			(at 1.610106 -2.899918)
			(size 0.2286 0.6096)
			(layers "F.Cu" "F.Mask" "F.Paste")
			(net "NC_PV09_RETIMER_CPU1_DNC1")
		)
		(pad "32" smd rect
			(at 1.160018 -2.899918)
			(size 0.2286 0.6096)
			(layers "F.Cu" "F.Mask" "F.Paste")
			(net "SW_P0V9_RETIMER_CPU1_PH1")
		)
		(pad "33" smd rect
			(at 0.70993 -2.899918)
			(size 0.2286 0.6096)
			(layers "F.Cu" "F.Mask" "F.Paste")
			(net "SW_P0V9_RETIMER_CPU1_BOOT1")
		)
		(pad "34" smd rect
			(at 0.260096 -2.899918)
			(size 0.2286 0.6096)
			(layers "F.Cu" "F.Mask" "F.Paste")
			(net "P0V9_RETIMER_CPU1_PWM1")
		)
		(pad "35" smd rect
			(at -0.189992 -2.899918)
			(size 0.2286 0.6096)
			(layers "F.Cu" "F.Mask" "F.Paste")
			(net "P0V9_RETIMER_CPU1_VCC1")
		)
		(pad "36" smd rect
			(at -0.64008 -2.899918)
			(size 0.2286 0.6096)
			(layers "F.Cu" "F.Mask" "F.Paste")
			(net "P0V9_RETIMER_CPU1_TEMP0")
		)
		(pad "37" smd rect
			(at -1.089914 -2.899918)
			(size 0.2286 0.6096)
			(layers "F.Cu" "F.Mask" "F.Paste")
			(net "P0V9_RETIMER_CPU1_LSET1")
		)
		(pad "38" smd rect
			(at -1.540002 -2.899918)
			(size 0.2286 0.6096)
			(layers "F.Cu" "F.Mask" "F.Paste")
			(net "P0V9_RETIMER_CPU1_IMON1")
		)
		(pad "39" smd rect
			(at -1.99009 -2.899918)
			(size 0.2286 0.6096)
			(layers "F.Cu" "F.Mask" "F.Paste")
			(net "PV09_RETIMER_CPU1_VCCS")
		)
		(pad "40" smd rect
			(at -0.87503 -1.27508)
			(size 1.7526 1.9558)
			(layers "F.Cu" "F.Mask" "F.Paste")
			(net "GND")
		)
		(pad "41" smd rect
			(at -1.525016 0.249936 270)
			(size 0.3048 0.4572)
			(layers "F.Cu" "F.Mask" "F.Paste")
			(net "NC_PV09_RETIMER_CPU1_GL2_1")
		)
		(zone
			(layer "F.Cu")
			(hatch none 0.5)
			(connect_pads
				(clearance 0)
			)
			(min_thickness 0.25)
			(keepout
				(tracks not_allowed)
				(vias allowed)
				(pads allowed)
				(copperpour not_allowed)
				(footprints allowed)
			)
			(placement
				(enabled no)
				(sheetname "")
			)
			(fill
				(thermal_gap 0.5)
				(thermal_bridge_width 0.5)
				(island_removal_mode 0)
			)
			(polygon
				(pts
					(xy 14.061948 -385.854194) (xy 14.061948 -386.603494) (xy 19.062192 -386.603494) (xy 19.062192 -385.854194)
					(xy 18.77187 -385.854194) (xy 18.77187 -386.30987) (xy 14.35227 -386.30987) (xy 14.35227 -385.854194)
				)
			)
		)
		(zone
			(layer "F.Cu")
			(hatch none 0.5)
			(connect_pads
				(clearance 0)
			)
			(min_thickness 0.25)
			(keepout
				(tracks not_allowed)
				(vias allowed)
				(pads allowed)
				(copperpour not_allowed)
				(footprints allowed)
			)
			(placement
				(enabled no)
				(sheetname "")
			)
			(fill
				(thermal_gap 0.5)
				(thermal_bridge_width 0.5)
				(island_removal_mode 0)
			)
			(polygon
				(pts
					(xy 14.061948 -388.104888) (xy 14.061948 -388.56158) (xy 14.757654 -388.56158) (xy 14.757654 -388.401052)
					(xy 15.316454 -388.401052) (xy 15.316454 -388.807452) (xy 14.757654 -388.807452) (xy 14.757654 -388.58698)
					(xy 14.061948 -388.58698) (xy 14.061948 -388.71398) (xy 14.517624 -388.71398) (xy 14.517624 -390.891522)
					(xy 14.75994 -390.891522) (xy 14.75994 -389.100568) (xy 16.61414 -389.100568) (xy 16.61414 -391.157968)
					(xy 14.75994 -391.157968) (xy 14.75994 -390.916922) (xy 14.517624 -390.916922) (xy 14.517624 -391.398506)
					(xy 19.062192 -391.398506) (xy 19.062192 -391.213594) (xy 16.905478 -391.213594) (xy 16.905478 -389.054594)
					(xy 19.062192 -389.054594) (xy 19.062192 -388.804912) (xy 15.611348 -388.804912) (xy 15.611348 -388.104888)
				)
			)
		)
	)
)
